(kicad_pcb
	(version 20260206)
	(generator "pcbnew")
	(generator_version "10.0")
	(general
		(thickness 1.6)
		(legacy_teardrops no)
	)
	(paper "A4")
	(title_block
		(title "9054_F0T_PDB_BD_GPU_F_V04_1213_1550_OCP.brd")
		(comment 1 "Grand Teton / footprints 386-392 of 608")
	)
	(layers
		(0 "F.Cu" signal "TOP")
		(4 "In1.Cu" signal "GND")
		(6 "In2.Cu" signal "IN1")
		(8 "In3.Cu" signal "GND1")
		(10 "In4.Cu" signal "VCC")
		(12 "In5.Cu" signal "VCC1")
		(14 "In6.Cu" signal "GND2")
		(16 "In7.Cu" signal "IN2")
		(18 "In8.Cu" signal "GND3")
		(2 "B.Cu" signal "BOTTOM")
		(9 "F.Adhes" user "F.Adhesive")
		(11 "B.Adhes" user "B.Adhesive")
		(13 "F.Paste" user "Package Geometry/Pastemask Top")
		(15 "B.Paste" user "Package Geometry/Pastemask Bottom")
		(5 "F.SilkS" user "Ref Des/Silkscreen Top")
		(7 "B.SilkS" user "Ref Des/Silkscreen Bottom")
		(1 "F.Mask" user "Board Geometry/Soldermask Top")
		(3 "B.Mask" user "Board Geometry/Soldermask Bottom")
		(17 "Dwgs.User" user "User.Drawings")
		(19 "Cmts.User" user "User.Comments")
		(21 "Eco1.User" user "User.Eco1")
		(23 "Eco2.User" user "User.Eco2")
		(25 "Edge.Cuts" user "Board Geometry/Outline")
		(27 "Margin" user)
		(31 "F.CrtYd" user "Package Geometry/Place Bound Top")
		(29 "B.CrtYd" user "Package Geometry/Place Bound Bottom")
		(35 "F.Fab" user "Ref Des/Assembly Top")
		(33 "B.Fab" user "Ref Des/Assembly Bottom")
	)
	(footprint ""
		(layer "F.Cu")
		(at 90.043 -50.3936)
		(property "Reference" "ME1"
			(at 0 0 0)
			(layer "F.SilkS")
			(hide yes)
			(effects
				(font
					(size 1.27 1.27)
				)
			)
		)
		(property "Value" ""
			(at 0 0 0)
			(layer "F.Fab")
			(effects
				(font
					(size 1.27 1.27)
				)
			)
		)
		(duplicate_pad_numbers_are_jumpers no)
	)
	(footprint ""
		(layer "F.Cu")
		(at 163.576 -63.881 180)
		(property "Reference" "PC614"
			(at 0 0 180)
			(layer "F.SilkS")
			(hide yes)
			(effects
				(font
					(size 1.27 1.27)
				)
			)
		)
		(property "Value" ""
			(at 0 0 180)
			(layer "F.Fab")
			(effects
				(font
					(size 1.27 1.27)
				)
			)
		)
		(duplicate_pad_numbers_are_jumpers no)
		(fp_line
			(start 1.2954 0.5842)
			(end -1.2954 0.5842)
			(stroke
				(width 0.1524)
				(type default)
			)
			(layer "F.SilkS")
		)
		(fp_line
			(start 1.2954 -0.5842)
			(end 1.2954 0.5842)
			(stroke
				(width 0.1524)
				(type default)
			)
			(layer "F.SilkS")
		)
		(fp_line
			(start -1.2954 0.5842)
			(end -1.2954 -0.5842)
			(stroke
				(width 0.1524)
				(type default)
			)
			(layer "F.SilkS")
		)
		(fp_line
			(start -1.2954 -0.5842)
			(end 1.2954 -0.5842)
			(stroke
				(width 0.1524)
				(type default)
			)
			(layer "F.SilkS")
		)
		(fp_line
			(start 1.1938 0.4064)
			(end 0.8636 0.4064)
			(stroke
				(width 0.1)
				(type default)
			)
			(layer "F.Fab")
		)
		(fp_line
			(start 1.1938 -0.4064)
			(end 1.1938 0.4064)
			(stroke
				(width 0.1)
				(type default)
			)
			(layer "F.Fab")
		)
		(fp_line
			(start 0.8636 0.4572)
			(end -0.8636 0.4572)
			(stroke
				(width 0.1)
				(type default)
			)
			(layer "F.Fab")
		)
		(fp_line
			(start 0.8636 0.4064)
			(end 0.8636 0.4572)
			(stroke
				(width 0.1)
				(type default)
			)
			(layer "F.Fab")
		)
		(fp_line
			(start 0.8636 -0.4064)
			(end 1.1938 -0.4064)
			(stroke
				(width 0.1)
				(type default)
			)
			(layer "F.Fab")
		)
		(fp_line
			(start 0.8636 -0.4572)
			(end 0.8636 -0.4064)
			(stroke
				(width 0.1)
				(type default)
			)
			(layer "F.Fab")
		)
		(fp_line
			(start -0.8636 0.4572)
			(end -0.8636 0.4064)
			(stroke
				(width 0.1)
				(type default)
			)
			(layer "F.Fab")
		)
		(fp_line
			(start -0.8636 0.4064)
			(end -1.1938 0.4064)
			(stroke
				(width 0.1)
				(type default)
			)
			(layer "F.Fab")
		)
		(fp_line
			(start -0.8636 -0.4064)
			(end -0.8636 -0.4572)
			(stroke
				(width 0.1)
				(type default)
			)
			(layer "F.Fab")
		)
		(fp_line
			(start -0.8636 -0.4572)
			(end 0.8636 -0.4572)
			(stroke
				(width 0.1)
				(type default)
			)
			(layer "F.Fab")
		)
		(fp_line
			(start -1.1938 0.4064)
			(end -1.1938 -0.4064)
			(stroke
				(width 0.1)
				(type default)
			)
			(layer "F.Fab")
		)
		(fp_line
			(start -1.1938 -0.4064)
			(end -0.8636 -0.4064)
			(stroke
				(width 0.1)
				(type default)
			)
			(layer "F.Fab")
		)
		(pad "1" smd rect
			(at -0.7366 0 90)
			(size 0.7112 0.8128)
			(layers "F.Cu" "F.Mask" "F.Paste")
			(net "P52V_HS2_ESTART")
		)
		(pad "2" smd rect
			(at 0.7366 0 90)
			(size 0.7112 0.8128)
			(layers "F.Cu" "F.Mask" "F.Paste")
			(net "GND1_FIELD_SIGNAL")
		)
	)
	(footprint ""
		(layer "F.Cu")
		(at 256.798318 -151.939498 90)
		(property "Reference" "J10"
			(at -3.222498 -5.819648 90)
			(unlocked yes)
			(layer "F.SilkS")
			(effects
				(font
					(size 0.7874 0.5842)
					(thickness 0.1524)
				)
				(justify left)
			)
		)
		(property "Value" ""
			(at 0 0 90)
			(layer "F.Fab")
			(effects
				(font
					(size 1.27 1.27)
				)
			)
		)
		(duplicate_pad_numbers_are_jumpers no)
		(fp_line
			(start 3.330702 -4.771136)
			(end 0 4.011168)
			(stroke
				(width 0.1524)
				(type default)
			)
			(layer "F.SilkS")
		)
		(fp_line
			(start -3.330702 -4.771136)
			(end 3.330702 -4.771136)
			(stroke
				(width 0.1524)
				(type default)
			)
			(layer "F.SilkS")
		)
		(fp_line
			(start 0 4.011168)
			(end -3.330702 -4.771136)
			(stroke
				(width 0.1524)
				(type default)
			)
			(layer "F.SilkS")
		)
		(fp_line
			(start 3.330702 -4.771136)
			(end 0 4.011168)
			(stroke
				(width 0.1)
				(type default)
			)
			(layer "F.Fab")
		)
		(fp_line
			(start -3.330702 -4.771136)
			(end 3.330702 -4.771136)
			(stroke
				(width 0.1)
				(type default)
			)
			(layer "F.Fab")
		)
		(fp_line
			(start 0 4.011168)
			(end -3.330702 -4.771136)
			(stroke
				(width 0.1)
				(type default)
			)
			(layer "F.Fab")
		)
		(pad "1" thru_hole circle
			(at 0 0 90)
			(size 2.159 2.159)
			(drill 1.7018)
			(layers "*.Cu" "*.Mask")
			(remove_unused_layers no)
			(net "GND3")
			(clearance 0.0254)
			(thermal_gap 0.0254)
		)
		(pad "2" thru_hole circle
			(at -1.27 -3.348736 90)
			(size 2.159 2.159)
			(drill 1.7018)
			(layers "*.Cu" "*.Mask")
			(remove_unused_layers no)
			(net "TDR_SE_50_OHM_TOP")
			(clearance 0.0254)
			(thermal_gap 0.0254)
		)
		(pad "3" thru_hole circle
			(at 1.27 -3.348736 90)
			(size 2.159 2.159)
			(drill 1.7018)
			(layers "*.Cu" "*.Mask")
			(remove_unused_layers no)
			(net "TDR_SE_50_OHM_TOP")
			(clearance 0.0254)
			(thermal_gap 0.0254)
		)
	)
	(footprint ""
		(layer "F.Cu")
		(at 431.8254 -31.3436 90)
		(property "Reference" "R62"
			(at 0 0 90)
			(layer "F.SilkS")
			(hide yes)
			(effects
				(font
					(size 1.27 1.27)
				)
			)
		)
		(property "Value" ""
			(at 0 0 90)
			(layer "F.Fab")
			(effects
				(font
					(size 1.27 1.27)
				)
			)
		)
		(duplicate_pad_numbers_are_jumpers no)
		(fp_line
			(start 0.7874 -0.4064)
			(end 0.7874 0.4064)
			(stroke
				(width 0.1524)
				(type default)
			)
			(layer "F.SilkS")
		)
		(fp_line
			(start -0.7874 -0.4064)
			(end 0.7874 -0.4064)
			(stroke
				(width 0.1524)
				(type default)
			)
			(layer "F.SilkS")
		)
		(fp_line
			(start 0.7874 0.4064)
			(end -0.7874 0.4064)
			(stroke
				(width 0.1524)
				(type default)
			)
			(layer "F.SilkS")
		)
		(fp_line
			(start -0.7874 0.4064)
			(end -0.7874 -0.4064)
			(stroke
				(width 0.1524)
				(type default)
			)
			(layer "F.SilkS")
		)
		(fp_line
			(start -0.12065 -0.305054)
			(end -0.12065 -0.2794)
			(stroke
				(width 0.1)
				(type default)
			)
			(layer "F.Fab")
		)
		(fp_line
			(start -0.67945 -0.305054)
			(end -0.12065 -0.305054)
			(stroke
				(width 0.1)
				(type default)
			)
			(layer "F.Fab")
		)
		(fp_line
			(start 0.67945 -0.3048)
			(end 0.67945 0.3048)
			(stroke
				(width 0.1)
				(type default)
			)
			(layer "F.Fab")
		)
		(fp_line
			(start 0.12065 -0.3048)
			(end 0.67945 -0.3048)
			(stroke
				(width 0.1)
				(type default)
			)
			(layer "F.Fab")
		)
		(fp_line
			(start 0.12065 -0.2794)
			(end 0.12065 -0.3048)
			(stroke
				(width 0.1)
				(type default)
			)
			(layer "F.Fab")
		)
		(fp_line
			(start -0.12065 -0.2794)
			(end 0.12065 -0.2794)
			(stroke
				(width 0.1)
				(type default)
			)
			(layer "F.Fab")
		)
		(fp_line
			(start 0.120396 0.2794)
			(end -0.12065 0.2794)
			(stroke
				(width 0.1)
				(type default)
			)
			(layer "F.Fab")
		)
		(fp_line
			(start -0.12065 0.2794)
			(end -0.12065 0.3048)
			(stroke
				(width 0.1)
				(type default)
			)
			(layer "F.Fab")
		)
		(fp_line
			(start 0.67945 0.3048)
			(end 0.120396 0.3048)
			(stroke
				(width 0.1)
				(type default)
			)
			(layer "F.Fab")
		)
		(fp_line
			(start 0.120396 0.3048)
			(end 0.120396 0.2794)
			(stroke
				(width 0.1)
				(type default)
			)
			(layer "F.Fab")
		)
		(fp_line
			(start -0.12065 0.3048)
			(end -0.67945 0.3048)
			(stroke
				(width 0.1)
				(type default)
			)
			(layer "F.Fab")
		)
		(fp_line
			(start -0.67945 0.3048)
			(end -0.67945 -0.305054)
			(stroke
				(width 0.1)
				(type default)
			)
			(layer "F.Fab")
		)
		(pad "1" smd circle
			(at -0.40005 0 90)
			(size 0 0)
			(layers "F.Cu" "F.Mask" "F.Paste")
			(net "SMB_FRU_DAT")
		)
		(pad "2" smd circle
			(at 0.40005 0 90)
			(size 0 0)
			(layers "F.Cu" "F.Mask" "F.Paste")
			(net "SMB_PDB_MISC_SDA")
		)
	)
	(footprint ""
		(layer "F.Cu")
		(at 169.672 -80.772 -90)
		(property "Reference" "C92"
			(at 0 0 270)
			(layer "F.SilkS")
			(hide yes)
			(effects
				(font
					(size 1.27 1.27)
				)
			)
		)
		(property "Value" ""
			(at 0 0 270)
			(layer "F.Fab")
			(effects
				(font
					(size 1.27 1.27)
				)
			)
		)
		(duplicate_pad_numbers_are_jumpers no)
		(fp_line
			(start -1.2954 0.5842)
			(end -1.2954 -0.5842)
			(stroke
				(width 0.1524)
				(type default)
			)
			(layer "F.SilkS")
		)
		(fp_line
			(start 1.2954 0.5842)
			(end -1.2954 0.5842)
			(stroke
				(width 0.1524)
				(type default)
			)
			(layer "F.SilkS")
		)
		(fp_line
			(start -1.2954 -0.5842)
			(end 1.2954 -0.5842)
			(stroke
				(width 0.1524)
				(type default)
			)
			(layer "F.SilkS")
		)
		(fp_line
			(start 1.2954 -0.5842)
			(end 1.2954 0.5842)
			(stroke
				(width 0.1524)
				(type default)
			)
			(layer "F.SilkS")
		)
		(fp_line
			(start -0.8636 0.4572)
			(end -0.8636 0.4064)
			(stroke
				(width 0.1)
				(type default)
			)
			(layer "F.Fab")
		)
		(fp_line
			(start 0.8636 0.4572)
			(end -0.8636 0.4572)
			(stroke
				(width 0.1)
				(type default)
			)
			(layer "F.Fab")
		)
		(fp_line
			(start -1.1938 0.4064)
			(end -1.1938 -0.4064)
			(stroke
				(width 0.1)
				(type default)
			)
			(layer "F.Fab")
		)
		(fp_line
			(start -0.8636 0.4064)
			(end -1.1938 0.4064)
			(stroke
				(width 0.1)
				(type default)
			)
			(layer "F.Fab")
		)
		(fp_line
			(start 0.8636 0.4064)
			(end 0.8636 0.4572)
			(stroke
				(width 0.1)
				(type default)
			)
			(layer "F.Fab")
		)
		(fp_line
			(start 1.1938 0.4064)
			(end 0.8636 0.4064)
			(stroke
				(width 0.1)
				(type default)
			)
			(layer "F.Fab")
		)
		(fp_line
			(start -1.1938 -0.4064)
			(end -0.8636 -0.4064)
			(stroke
				(width 0.1)
				(type default)
			)
			(layer "F.Fab")
		)
		(fp_line
			(start -0.8636 -0.4064)
			(end -0.8636 -0.4572)
			(stroke
				(width 0.1)
				(type default)
			)
			(layer "F.Fab")
		)
		(fp_line
			(start 0.8636 -0.4064)
			(end 1.1938 -0.4064)
			(stroke
				(width 0.1)
				(type default)
			)
			(layer "F.Fab")
		)
		(fp_line
			(start 1.1938 -0.4064)
			(end 1.1938 0.4064)
			(stroke
				(width 0.1)
				(type default)
			)
			(layer "F.Fab")
		)
		(fp_line
			(start -0.8636 -0.4572)
			(end 0.8636 -0.4572)
			(stroke
				(width 0.1)
				(type default)
			)
			(layer "F.Fab")
		)
		(fp_line
			(start 0.8636 -0.4572)
			(end 0.8636 -0.4064)
			(stroke
				(width 0.1)
				(type default)
			)
			(layer "F.Fab")
		)
		(pad "1" smd rect
			(at -0.7366 0 180)
			(size 0.7112 0.8128)
			(layers "F.Cu" "F.Mask" "F.Paste")
			(net "FM_HS2_EN_BUSBAR")
		)
		(pad "2" smd rect
			(at 0.7366 0 180)
			(size 0.7112 0.8128)
			(layers "F.Cu" "F.Mask" "F.Paste")
			(net "GND")
		)
	)
	(footprint ""
		(layer "B.Cu")
		(at 161.717736 -66.04)
		(property "Reference" "R5872"
			(at 0 0 0)
			(layer "B.SilkS")
			(hide yes)
			(effects
				(font
					(size 1.27 1.27)
				)
				(justify mirror)
			)
		)
		(property "Value" ""
			(at 0 0 0)
			(layer "B.Fab")
			(effects
				(font
					(size 1.27 1.27)
				)
				(justify mirror)
			)
		)
		(duplicate_pad_numbers_are_jumpers no)
		(fp_line
			(start -0.7874 -0.4064)
			(end -0.7874 0.4064)
			(stroke
				(width 0.1524)
				(type default)
			)
			(layer "B.SilkS")
		)
		(fp_line
			(start -0.7874 0.4064)
			(end 0.7874 0.4064)
			(stroke
				(width 0.1524)
				(type default)
			)
			(layer "B.SilkS")
		)
		(fp_line
			(start 0.7874 -0.4064)
			(end -0.7874 -0.4064)
			(stroke
				(width 0.1524)
				(type default)
			)
			(layer "B.SilkS")
		)
		(fp_line
			(start 0.7874 0.4064)
			(end 0.7874 -0.4064)
			(stroke
				(width 0.1524)
				(type default)
			)
			(layer "B.SilkS")
		)
		(fp_line
			(start -0.67945 -0.3048)
			(end -0.67945 0.3048)
			(stroke
				(width 0.1)
				(type default)
			)
			(layer "B.Fab")
		)
		(fp_line
			(start -0.67945 0.3048)
			(end -0.120396 0.3048)
			(stroke
				(width 0.1)
				(type default)
			)
			(layer "B.Fab")
		)
		(fp_line
			(start -0.12065 -0.3048)
			(end -0.67945 -0.3048)
			(stroke
				(width 0.1)
				(type default)
			)
			(layer "B.Fab")
		)
		(fp_line
			(start -0.12065 -0.2794)
			(end -0.12065 -0.3048)
			(stroke
				(width 0.1)
				(type default)
			)
			(layer "B.Fab")
		)
		(fp_line
			(start -0.120396 0.2794)
			(end 0.12065 0.2794)
			(stroke
				(width 0.1)
				(type default)
			)
			(layer "B.Fab")
		)
		(fp_line
			(start -0.120396 0.3048)
			(end -0.120396 0.2794)
			(stroke
				(width 0.1)
				(type default)
			)
			(layer "B.Fab")
		)
		(fp_line
			(start 0.12065 -0.305054)
			(end 0.12065 -0.2794)
			(stroke
				(width 0.1)
				(type default)
			)
			(layer "B.Fab")
		)
		(fp_line
			(start 0.12065 -0.2794)
			(end -0.12065 -0.2794)
			(stroke
				(width 0.1)
				(type default)
			)
			(layer "B.Fab")
		)
		(fp_line
			(start 0.12065 0.2794)
			(end 0.12065 0.3048)
			(stroke
				(width 0.1)
				(type default)
			)
			(layer "B.Fab")
		)
		(fp_line
			(start 0.12065 0.3048)
			(end 0.67945 0.3048)
			(stroke
				(width 0.1)
				(type default)
			)
			(layer "B.Fab")
		)
		(fp_line
			(start 0.67945 -0.305054)
			(end 0.12065 -0.305054)
			(stroke
				(width 0.1)
				(type default)
			)
			(layer "B.Fab")
		)
		(fp_line
			(start 0.67945 0.3048)
			(end 0.67945 -0.305054)
			(stroke
				(width 0.1)
				(type default)
			)
			(layer "B.Fab")
		)
		(pad "1" smd circle
			(at 0.40005 0 180)
			(size 0 0)
			(layers "B.Cu" "B.Mask" "B.Paste")
			(net "SMB_P52V_PDB_SDA")
		)
		(pad "2" smd circle
			(at -0.40005 0 180)
			(size 0 0)
			(layers "B.Cu" "B.Mask" "B.Paste")
			(net "SMB_P52V_HS2_SDAO")
		)
	)
	(footprint ""
		(layer "B.Cu")
		(at 336.3214 -39.37 -90)
		(property "Reference" "R5861"
			(at 0 0 90)
			(layer "B.SilkS")
			(hide yes)
			(effects
				(font
					(size 1.27 1.27)
				)
				(justify mirror)
			)
		)
		(property "Value" ""
			(at 0 0 90)
			(layer "B.Fab")
			(effects
				(font
					(size 1.27 1.27)
				)
				(justify mirror)
			)
		)
		(duplicate_pad_numbers_are_jumpers no)
		(fp_line
			(start -0.7874 0.4064)
			(end 0.7874 0.4064)
			(stroke
				(width 0.1524)
				(type default)
			)
			(layer "B.SilkS")
		)
		(fp_line
			(start 0.7874 0.4064)
			(end 0.7874 -0.4064)
			(stroke
				(width 0.1524)
				(type default)
			)
			(layer "B.SilkS")
		)
		(fp_line
			(start -0.7874 -0.4064)
			(end -0.7874 0.4064)
			(stroke
				(width 0.1524)
				(type default)
			)
			(layer "B.SilkS")
		)
		(fp_line
			(start 0.7874 -0.4064)
			(end -0.7874 -0.4064)
			(stroke
				(width 0.1524)
				(type default)
			)
			(layer "B.SilkS")
		)
		(fp_line
			(start -0.67945 0.3048)
			(end -0.120396 0.3048)
			(stroke
				(width 0.1)
				(type default)
			)
			(layer "B.Fab")
		)
		(fp_line
			(start -0.120396 0.3048)
			(end -0.120396 0.2794)
			(stroke
				(width 0.1)
				(type default)
			)
			(layer "B.Fab")
		)
		(fp_line
			(start 0.12065 0.3048)
			(end 0.67945 0.3048)
			(stroke
				(width 0.1)
				(type default)
			)
			(layer "B.Fab")
		)
		(fp_line
			(start 0.67945 0.3048)
			(end 0.67945 -0.305054)
			(stroke
				(width 0.1)
				(type default)
			)
			(layer "B.Fab")
		)
		(fp_line
			(start -0.120396 0.2794)
			(end 0.12065 0.2794)
			(stroke
				(width 0.1)
				(type default)
			)
			(layer "B.Fab")
		)
		(fp_line
			(start 0.12065 0.2794)
			(end 0.12065 0.3048)
			(stroke
				(width 0.1)
				(type default)
			)
			(layer "B.Fab")
		)
		(fp_line
			(start -0.12065 -0.2794)
			(end -0.12065 -0.3048)
			(stroke
				(width 0.1)
				(type default)
			)
			(layer "B.Fab")
		)
		(fp_line
			(start 0.12065 -0.2794)
			(end -0.12065 -0.2794)
			(stroke
				(width 0.1)
				(type default)
			)
			(layer "B.Fab")
		)
		(fp_line
			(start -0.67945 -0.3048)
			(end -0.67945 0.3048)
			(stroke
				(width 0.1)
				(type default)
			)
			(layer "B.Fab")
		)
		(fp_line
			(start -0.12065 -0.3048)
			(end -0.67945 -0.3048)
			(stroke
				(width 0.1)
				(type default)
			)
			(layer "B.Fab")
		)
		(fp_line
			(start 0.12065 -0.305054)
			(end 0.12065 -0.2794)
			(stroke
				(width 0.1)
				(type default)
			)
			(layer "B.Fab")
		)
		(fp_line
			(start 0.67945 -0.305054)
			(end 0.12065 -0.305054)
			(stroke
				(width 0.1)
				(type default)
			)
			(layer "B.Fab")
		)
		(pad "1" smd circle
			(at 0.40005 0 90)
			(size 0 0)
			(layers "B.Cu" "B.Mask" "B.Paste")
			(net "P52V_HS1_1272_GATE")
		)
		(pad "2" smd circle
			(at -0.40005 0 90)
			(size 0 0)
			(layers "B.Cu" "B.Mask" "B.Paste")
			(net "P52V_HS1_GATE2_R")
		)
	)
)
